(kicad_pcb
	(version 20260206)
	(generator "pcbnew")
	(generator_version "10.0")
	(general
		(thickness 1.6)
		(legacy_teardrops no)
	)
	(paper "A4")
	(title_block
		(title "Bryce Canyon_F.DPB_16315-1-OCP.brd")
		(comment 1 "Bryce Canyon / footprints 461-465 of 2223")
	)
	(layers
		(0 "F.Cu" signal "TOP")
		(4 "In1.Cu" signal "L2GND")
		(6 "In2.Cu" signal "L3")
		(8 "In3.Cu" signal "L4GND")
		(10 "In4.Cu" signal "L5")
		(12 "In5.Cu" signal "L6VCC")
		(14 "In6.Cu" signal "L7VCC")
		(16 "In7.Cu" signal "L8")
		(18 "In8.Cu" signal "L9GND")
		(20 "In9.Cu" signal "L10")
		(22 "In10.Cu" signal "L11GND")
		(2 "B.Cu" signal "BOTTOM")
		(9 "F.Adhes" user "F.Adhesive")
		(11 "B.Adhes" user "B.Adhesive")
		(13 "F.Paste" user "Package Geometry/Pastemask Top")
		(15 "B.Paste" user "Package Geometry/Pastemask Bottom")
		(5 "F.SilkS" user "Ref Des/Silkscreen Top")
		(7 "B.SilkS" user "Ref Des/Silkscreen Bottom")
		(1 "F.Mask" user "Board Geometry/Soldermask Top")
		(3 "B.Mask" user "Board Geometry/Soldermask Bottom")
		(17 "Dwgs.User" user "User.Drawings")
		(19 "Cmts.User" user "User.Comments")
		(21 "Eco1.User" user "User.Eco1")
		(23 "Eco2.User" user "User.Eco2")
		(25 "Edge.Cuts" user "Board Geometry/Outline")
		(27 "Margin" user)
		(31 "F.CrtYd" user "Package Geometry/Place Bound Top")
		(29 "B.CrtYd" user "Package Geometry/Place Bound Bottom")
		(35 "F.Fab" user "Ref Des/Assembly Top")
		(33 "B.Fab" user "Ref Des/Assembly Bottom")
	)
	(footprint ""
		(layer "F.Cu")
		(at 224.572322 -132.79247 -90)
		(property "Reference" "TP206"
			(at 0 0 270)
			(layer "F.SilkS")
			(hide yes)
			(effects
				(font
					(size 1.27 1.27)
				)
			)
		)
		(property "Value" "TPAD32-GP"
			(at -0.0508 -1.6764 270)
			(unlocked yes)
			(layer "F.Fab")
			(hide yes)
			(effects
				(font
					(size 1.016 1.016)
					(thickness 0.1524)
				)
			)
		)
		(property "Device Type" "TPAD32"
			(at -0.0508 -3.2004 270)
			(unlocked yes)
			(layer "F.Fab")
			(hide yes)
			(effects
				(font
					(size 1.016 1.016)
					(thickness 0.1524)
				)
			)
		)
		(duplicate_pad_numbers_are_jumpers no)
		(fp_poly
			(pts
				(arc
					(start 0 -0.4064)
					(mid 0 0.4064)
					(end 0 -0.4064)
				)
			)
			(stroke
				(width 0)
				(type default)
			)
			(fill no)
			(layer "F.CrtYd")
		)
		(fp_poly
			(pts
				(arc
					(start 0 -0.7112)
					(mid 0 0.7112)
					(end 0 -0.7112)
				)
			)
			(stroke
				(width 0)
				(type default)
			)
			(fill no)
			(layer "F.Fab")
		)
		(pad "1" smd circle
			(at 0 0 270)
			(size 0.8128 0.8128)
			(layers "F.Cu" "F.Mask" "F.Paste")
			(net "TP_COMP_A_SATA_P0_RX_DN")
		)
	)
	(footprint ""
		(layer "F.Cu")
		(at 270.223234 20.568412 90)
		(property "Reference" "R141"
			(at 0 0 90)
			(layer "F.SilkS")
			(hide yes)
			(effects
				(font
					(size 1.27 1.27)
				)
			)
		)
		(property "Value" "4K7R2F-GP"
			(at 0.064008 -3.993896 90)
			(unlocked yes)
			(layer "F.Fab")
			(hide yes)
			(effects
				(font
					(size 1.016 1.016)
					(thickness 0.1524)
				)
			)
		)
		(property "Device Type" "R402H16"
			(at 0.064008 -5.517896 90)
			(unlocked yes)
			(layer "F.Fab")
			(hide yes)
			(effects
				(font
					(size 1.016 1.016)
					(thickness 0.1524)
				)
			)
		)
		(duplicate_pad_numbers_are_jumpers no)
		(fp_line
			(start 0.508 -0.9398)
			(end -0.508 -0.9398)
			(stroke
				(width 0.1524)
				(type default)
			)
			(layer "F.SilkS")
		)
		(fp_line
			(start -0.508 -0.9398)
			(end -0.508 0.9398)
			(stroke
				(width 0.1524)
				(type default)
			)
			(layer "F.SilkS")
		)
		(fp_rect
			(start -0.508 0.9398)
			(end 0.508 -0.9398)
			(stroke
				(width 0)
				(type default)
			)
			(fill no)
			(layer "F.CrtYd")
		)
		(fp_rect
			(start -0.508 0.9398)
			(end 0.508 -0.9398)
			(stroke
				(width 0)
				(type default)
			)
			(fill no)
			(layer "F.Fab")
		)
		(pad "1" smd custom
			(at 0 -0.4445 90)
			(size 0.1397 0.1397)
			(layers "F.Cu" "F.Mask" "F.Paste")
			(net "USB_OCS_N2")
			(options
				(clearance outline)
				(anchor circle)
			)
			(primitives
				(gr_poly
					(pts
						(arc
							(start -0.1778 -0.2794)
							(mid -0.249642 -0.249642)
							(end -0.2794 -0.1778)
						)
						(arc
							(start -0.2794 0.1778)
							(mid -0.249642 0.249642)
							(end -0.1778 0.2794)
						)
						(arc
							(start 0.1778 0.2794)
							(mid 0.249642 0.249642)
							(end 0.2794 0.1778)
						)
						(arc
							(start 0.2794 -0.1778)
							(mid 0.249642 -0.249642)
							(end 0.1778 -0.2794)
						)
					)
					(width 0)
					(fill yes)
				)
			)
		)
		(pad "2" smd custom
			(at 0 0.4445 90)
			(size 0.1397 0.1397)
			(layers "F.Cu" "F.Mask" "F.Paste")
			(net "GND")
			(options
				(clearance outline)
				(anchor circle)
			)
			(primitives
				(gr_poly
					(pts
						(arc
							(start -0.1778 -0.2794)
							(mid -0.249642 -0.249642)
							(end -0.2794 -0.1778)
						)
						(arc
							(start -0.2794 0.1778)
							(mid -0.249642 0.249642)
							(end -0.1778 0.2794)
						)
						(arc
							(start 0.1778 0.2794)
							(mid 0.249642 0.249642)
							(end 0.2794 0.1778)
						)
						(arc
							(start 0.2794 -0.1778)
							(mid 0.249642 -0.249642)
							(end 0.1778 -0.2794)
						)
					)
					(width 0)
					(fill yes)
				)
			)
		)
	)
	(footprint ""
		(layer "F.Cu")
		(at 161.743898 -68.697094)
		(property "Reference" "TP142"
			(at 0 0 0)
			(layer "F.SilkS")
			(hide yes)
			(effects
				(font
					(size 1.27 1.27)
				)
			)
		)
		(property "Value" "TPAD32-GP"
			(at -0.0508 -1.6764 0)
			(unlocked yes)
			(layer "F.Fab")
			(hide yes)
			(effects
				(font
					(size 1.016 1.016)
					(thickness 0.1524)
				)
			)
		)
		(property "Device Type" "TPAD32"
			(at -0.0508 -3.2004 0)
			(unlocked yes)
			(layer "F.Fab")
			(hide yes)
			(effects
				(font
					(size 1.016 1.016)
					(thickness 0.1524)
				)
			)
		)
		(duplicate_pad_numbers_are_jumpers no)
		(fp_poly
			(pts
				(arc
					(start 0.4064 0)
					(mid -0.4064 0)
					(end 0.4064 0)
				)
			)
			(stroke
				(width 0)
				(type default)
			)
			(fill no)
			(layer "F.CrtYd")
		)
		(fp_poly
			(pts
				(arc
					(start 0.7112 0)
					(mid -0.7112 0)
					(end 0.7112 0)
				)
			)
			(stroke
				(width 0)
				(type default)
			)
			(fill no)
			(layer "F.Fab")
		)
		(pad "1" smd circle
			(at 0 0)
			(size 0.8128 0.8128)
			(layers "F.Cu" "F.Mask" "F.Paste")
			(net "ACT_HDD_28")
		)
	)
	(footprint ""
		(layer "F.Cu")
		(at 77.942948 -284.523942 90)
		(property "Reference" "C75"
			(at 0 0 90)
			(layer "F.SilkS")
			(hide yes)
			(effects
				(font
					(size 1.27 1.27)
				)
			)
		)
		(property "Value" "SCD033U25V2KX-GP"
			(at 1.1811 -2.7051 90)
			(unlocked yes)
			(layer "F.Fab")
			(hide yes)
			(effects
				(font
					(size 1.016 1.016)
					(thickness 0.1524)
				)
			)
		)
		(property "Device Type" "C402H22"
			(at 1.1811 -4.2291 90)
			(unlocked yes)
			(layer "F.Fab")
			(hide yes)
			(effects
				(font
					(size 1.016 1.016)
					(thickness 0.1524)
				)
			)
		)
		(duplicate_pad_numbers_are_jumpers no)
		(fp_rect
			(start -0.4318 0.9525)
			(end 0.4318 -0.9525)
			(stroke
				(width 0)
				(type default)
			)
			(fill no)
			(layer "F.CrtYd")
		)
		(fp_rect
			(start -0.4318 0.9525)
			(end 0.4318 -0.9525)
			(stroke
				(width 0)
				(type default)
			)
			(fill no)
			(layer "F.Fab")
		)
		(pad "1" smd custom
			(at 0 -0.4445 90)
			(size 0.1524 0.1524)
			(layers "F.Cu" "F.Mask" "F.Paste")
			(net "P12V_A")
			(options
				(clearance outline)
				(anchor circle)
			)
			(primitives
				(gr_poly
					(pts
						(arc
							(start 0.3048 -0.2032)
							(mid 0.275042 -0.275042)
							(end 0.2032 -0.3048)
						)
						(arc
							(start -0.2032 -0.3048)
							(mid -0.275042 -0.275042)
							(end -0.3048 -0.2032)
						)
						(arc
							(start -0.3048 0.2032)
							(mid -0.275042 0.275042)
							(end -0.2032 0.3048)
						)
						(arc
							(start 0.2032 0.3048)
							(mid 0.275042 0.275042)
							(end 0.3048 0.2032)
						)
					)
					(width 0)
					(fill yes)
				)
			)
		)
		(pad "2" smd custom
			(at 0 0.4445 90)
			(size 0.1524 0.1524)
			(layers "F.Cu" "F.Mask" "F.Paste")
			(net "SW_HDD_N2")
			(options
				(clearance outline)
				(anchor circle)
			)
			(primitives
				(gr_poly
					(pts
						(arc
							(start 0.3048 -0.2032)
							(mid 0.275042 -0.275042)
							(end 0.2032 -0.3048)
						)
						(arc
							(start -0.2032 -0.3048)
							(mid -0.275042 -0.275042)
							(end -0.3048 -0.2032)
						)
						(arc
							(start -0.3048 0.2032)
							(mid -0.275042 0.275042)
							(end -0.2032 0.3048)
						)
						(arc
							(start 0.2032 0.3048)
							(mid 0.275042 0.275042)
							(end 0.3048 0.2032)
						)
					)
					(width 0)
					(fill yes)
				)
			)
		)
	)
	(footprint ""
		(layer "F.Cu")
		(at 130.193796 -68.747894)
		(property "Reference" "TP137"
			(at 0 0 0)
			(layer "F.SilkS")
			(hide yes)
			(effects
				(font
					(size 1.27 1.27)
				)
			)
		)
		(property "Value" "TPAD32-GP"
			(at -0.0508 -1.6764 0)
			(unlocked yes)
			(layer "F.Fab")
			(hide yes)
			(effects
				(font
					(size 1.016 1.016)
					(thickness 0.1524)
				)
			)
		)
		(property "Device Type" "TPAD32"
			(at -0.0508 -3.2004 0)
			(unlocked yes)
			(layer "F.Fab")
			(hide yes)
			(effects
				(font
					(size 1.016 1.016)
					(thickness 0.1524)
				)
			)
		)
		(duplicate_pad_numbers_are_jumpers no)
		(fp_poly
			(pts
				(arc
					(start 0.4064 0)
					(mid -0.4064 0)
					(end 0.4064 0)
				)
			)
			(stroke
				(width 0)
				(type default)
			)
			(fill no)
			(layer "F.CrtYd")
		)
		(fp_poly
			(pts
				(arc
					(start 0.7112 0)
					(mid -0.7112 0)
					(end 0.7112 0)
				)
			)
			(stroke
				(width 0)
				(type default)
			)
			(fill no)
			(layer "F.Fab")
		)
		(pad "1" smd circle
			(at 0 0)
			(size 0.8128 0.8128)
			(layers "F.Cu" "F.Mask" "F.Paste")
			(net "ACT_HDD_27")
		)
	)
)
